# T6G (Grand Teton) — schematic netlist excerpt (pin names and nets, part order shuffled) for the footprints in the layout excerpt that follows; sources: Cadence DE-HDL packaged netlist, KiCad conversion of 04192023_DAF0TMB3IC0_F0TG_MB_C_brd_V02_OCP.brd

C8008  Q_CAP  0.1UF 25V 10% X7R  pkg 0402  page 136 : A = P3V3_OCP_SFF_R ; B = GND
PC432  Q_CAP  2.2UF 10V 10% X6S  pkg C0402  page 222 : A = PVDDIO_P1_VCC2 ; B = GND

(kicad_pcb
	(version 20260206)
	(generator "pcbnew")
	(generator_version "10.0")
	(general
		(thickness 1.6)
		(legacy_teardrops no)
	)
	(paper "A4")
	(title_block
		(title "04192023_DAF0TMB3IC0_F0TG_MB_C_brd_V02_OCP.brd")
		(comment 1 "Grand Teton / footprints 2143-2144 of 8354")
	)
	(layers
		(0 "F.Cu" signal "TOP")
		(4 "In1.Cu" signal "GND")
		(6 "In2.Cu" signal "IN1")
		(8 "In3.Cu" signal "GND1")
		(10 "In4.Cu" signal "IN2")
		(12 "In5.Cu" signal "GND2")
		(14 "In6.Cu" signal "IN3")
		(16 "In7.Cu" signal "GND3")
		(18 "In8.Cu" signal "VCC")
		(20 "In9.Cu" signal "VCC1")
		(22 "In10.Cu" signal "GND4")
		(24 "In11.Cu" signal "IN4")
		(26 "In12.Cu" signal "GND5")
		(28 "In13.Cu" signal "IN5")
		(30 "In14.Cu" signal "GND6")
		(32 "In15.Cu" signal "IN6")
		(34 "In16.Cu" signal "GND7")
		(2 "B.Cu" signal "BOTTOM")
		(9 "F.Adhes" user "F.Adhesive")
		(11 "B.Adhes" user "B.Adhesive")
		(13 "F.Paste" user "Package Geometry/Pastemask Top")
		(15 "B.Paste" user "Package Geometry/Pastemask Bottom")
		(5 "F.SilkS" user "Ref Des/Silkscreen Top")
		(7 "B.SilkS" user "Ref Des/Silkscreen Bottom")
		(1 "F.Mask" user "Board Geometry/Soldermask Top")
		(3 "B.Mask" user "Board Geometry/Soldermask Bottom")
		(17 "Dwgs.User" user "User.Drawings")
		(19 "Cmts.User" user "User.Comments")
		(21 "Eco1.User" user "User.Eco1")
		(23 "Eco2.User" user "User.Eco2")
		(25 "Edge.Cuts" user "Board Geometry/Outline")
		(27 "Margin" user)
		(31 "F.CrtYd" user "Package Geometry/Place Bound Top")
		(29 "B.CrtYd" user "Package Geometry/Place Bound Bottom")
		(35 "F.Fab" user "Ref Des/Assembly Top")
		(33 "B.Fab" user "Ref Des/Assembly Bottom")
	)
	(footprint ""
		(layer "F.Cu")
		(at 41.503854 -349.386398 90)
		(property "Reference" "PC432"
			(at 0 0 90)
			(layer "F.SilkS")
			(hide yes)
			(effects
				(font
					(size 1.27 1.27)
				)
			)
		)
		(property "Value" ""
			(at 0 0 90)
			(layer "F.Fab")
			(effects
				(font
					(size 1.27 1.27)
				)
			)
		)
		(duplicate_pad_numbers_are_jumpers no)
		(fp_line
			(start 0.7874 -0.4064)
			(end 0.7874 0.4064)
			(stroke
				(width 0.1524)
				(type default)
			)
			(layer "F.SilkS")
		)
		(fp_line
			(start -0.7874 -0.4064)
			(end 0.7874 -0.4064)
			(stroke
				(width 0.1524)
				(type default)
			)
			(layer "F.SilkS")
		)
		(fp_line
			(start 0.7874 0.4064)
			(end 0.498602 0.4064)
			(stroke
				(width 0.1524)
				(type default)
			)
			(layer "F.SilkS")
		)
		(fp_line
			(start -0.314198 0.4064)
			(end -0.7874 0.4064)
			(stroke
				(width 0.1524)
				(type default)
			)
			(layer "F.SilkS")
		)
		(fp_line
			(start -0.7874 0.4064)
			(end -0.7874 -0.4064)
			(stroke
				(width 0.1524)
				(type default)
			)
			(layer "F.SilkS")
		)
		(fp_line
			(start -0.12065 -0.305054)
			(end -0.12065 -0.2794)
			(stroke
				(width 0.1)
				(type default)
			)
			(layer "F.Fab")
		)
		(fp_line
			(start -0.67945 -0.305054)
			(end -0.12065 -0.305054)
			(stroke
				(width 0.1)
				(type default)
			)
			(layer "F.Fab")
		)
		(fp_line
			(start 0.67945 -0.3048)
			(end 0.67945 0.3048)
			(stroke
				(width 0.1)
				(type default)
			)
			(layer "F.Fab")
		)
		(fp_line
			(start 0.12065 -0.3048)
			(end 0.67945 -0.3048)
			(stroke
				(width 0.1)
				(type default)
			)
			(layer "F.Fab")
		)
		(fp_line
			(start 0.12065 -0.2794)
			(end 0.12065 -0.3048)
			(stroke
				(width 0.1)
				(type default)
			)
			(layer "F.Fab")
		)
		(fp_line
			(start -0.12065 -0.2794)
			(end 0.12065 -0.2794)
			(stroke
				(width 0.1)
				(type default)
			)
			(layer "F.Fab")
		)
		(fp_line
			(start 0.120396 0.2794)
			(end -0.12065 0.2794)
			(stroke
				(width 0.1)
				(type default)
			)
			(layer "F.Fab")
		)
		(fp_line
			(start -0.12065 0.2794)
			(end -0.12065 0.3048)
			(stroke
				(width 0.1)
				(type default)
			)
			(layer "F.Fab")
		)
		(fp_line
			(start 0.67945 0.3048)
			(end 0.120396 0.3048)
			(stroke
				(width 0.1)
				(type default)
			)
			(layer "F.Fab")
		)
		(fp_line
			(start 0.120396 0.3048)
			(end 0.120396 0.2794)
			(stroke
				(width 0.1)
				(type default)
			)
			(layer "F.Fab")
		)
		(fp_line
			(start -0.12065 0.3048)
			(end -0.67945 0.3048)
			(stroke
				(width 0.1)
				(type default)
			)
			(layer "F.Fab")
		)
		(fp_line
			(start -0.67945 0.3048)
			(end -0.67945 -0.305054)
			(stroke
				(width 0.1)
				(type default)
			)
			(layer "F.Fab")
		)
		(pad "1" smd circle
			(at -0.40005 0 90)
			(size 0 0)
			(layers "F.Cu" "F.Mask" "F.Paste")
			(net "PVDDIO_P1_VCC2")
		)
		(pad "2" smd circle
			(at 0.40005 0 90)
			(size 0 0)
			(layers "F.Cu" "F.Mask" "F.Paste")
			(net "GND")
		)
	)
	(footprint ""
		(layer "F.Cu")
		(at 415.798 -96.901 180)
		(property "Reference" "C8008"
			(at 0 0 180)
			(layer "F.SilkS")
			(hide yes)
			(effects
				(font
					(size 1.27 1.27)
				)
			)
		)
		(property "Value" ""
			(at 0 0 180)
			(layer "F.Fab")
			(effects
				(font
					(size 1.27 1.27)
				)
			)
		)
		(duplicate_pad_numbers_are_jumpers no)
		(fp_line
			(start 0.7874 0.4064)
			(end -0.7874 0.4064)
			(stroke
				(width 0.1524)
				(type default)
			)
			(layer "F.SilkS")
		)
		(fp_line
			(start 0.7874 -0.4064)
			(end 0.7874 0.4064)
			(stroke
				(width 0.1524)
				(type default)
			)
			(layer "F.SilkS")
		)
		(fp_line
			(start -0.7874 0.4064)
			(end -0.7874 -0.4064)
			(stroke
				(width 0.1524)
				(type default)
			)
			(layer "F.SilkS")
		)
		(fp_line
			(start -0.7874 -0.4064)
			(end 0.7874 -0.4064)
			(stroke
				(width 0.1524)
				(type default)
			)
			(layer "F.SilkS")
		)
		(fp_line
			(start 0.67945 0.3048)
			(end 0.120396 0.3048)
			(stroke
				(width 0.1)
				(type default)
			)
			(layer "F.Fab")
		)
		(fp_line
			(start 0.67945 -0.3048)
			(end 0.67945 0.3048)
			(stroke
				(width 0.1)
				(type default)
			)
			(layer "F.Fab")
		)
		(fp_line
			(start 0.12065 -0.2794)
			(end 0.12065 -0.3048)
			(stroke
				(width 0.1)
				(type default)
			)
			(layer "F.Fab")
		)
		(fp_line
			(start 0.12065 -0.3048)
			(end 0.67945 -0.3048)
			(stroke
				(width 0.1)
				(type default)
			)
			(layer "F.Fab")
		)
		(fp_line
			(start 0.120396 0.3048)
			(end 0.120396 0.2794)
			(stroke
				(width 0.1)
				(type default)
			)
			(layer "F.Fab")
		)
		(fp_line
			(start 0.120396 0.2794)
			(end -0.12065 0.2794)
			(stroke
				(width 0.1)
				(type default)
			)
			(layer "F.Fab")
		)
		(fp_line
			(start -0.12065 0.3048)
			(end -0.67945 0.3048)
			(stroke
				(width 0.1)
				(type default)
			)
			(layer "F.Fab")
		)
		(fp_line
			(start -0.12065 0.2794)
			(end -0.12065 0.3048)
			(stroke
				(width 0.1)
				(type default)
			)
			(layer "F.Fab")
		)
		(fp_line
			(start -0.12065 -0.2794)
			(end 0.12065 -0.2794)
			(stroke
				(width 0.1)
				(type default)
			)
			(layer "F.Fab")
		)
		(fp_line
			(start -0.12065 -0.305054)
			(end -0.12065 -0.2794)
			(stroke
				(width 0.1)
				(type default)
			)
			(layer "F.Fab")
		)
		(fp_line
			(start -0.67945 0.3048)
			(end -0.67945 -0.305054)
			(stroke
				(width 0.1)
				(type default)
			)
			(layer "F.Fab")
		)
		(fp_line
			(start -0.67945 -0.305054)
			(end -0.12065 -0.305054)
			(stroke
				(width 0.1)
				(type default)
			)
			(layer "F.Fab")
		)
		(pad "1" smd circle
			(at -0.40005 0 180)
			(size 0 0)
			(layers "F.Cu" "F.Mask" "F.Paste")
			(net "P3V3_OCP_SFF_R")
		)
		(pad "2" smd circle
			(at 0.40005 0 180)
			(size 0 0)
			(layers "F.Cu" "F.Mask" "F.Paste")
			(net "GND")
		)
	)
)
